# BASEBOARD_FAB2 (Tioga Pass) — schematic netlist excerpt (pin names and nets, part order shuffled) for the footprints in the layout excerpt that follows; sources: Cadence DE-HDL packaged netlist, KiCad conversion of Wiwynn_Tioga_Pass_MB.brd

C5G61  CAP_A  22.0UF 4V 20% X6S  pkg 0603V  page 242 : A = PVDDQ_DEF ; B = GND
C2U27  CAP_A  0.1UF 16V 10% X7R  pkg 0402V  page 161 : A = P3V3_STBY ; B = GND

Q4U1  FET_N_DUAL  NTJD4001N FET  pkg SMLF  page 94
  SOURCE(0)  = GND
  GATE(0)  = FM_DIMM_EVENT_COD_N
  DRAIN(0)  = FM_MEM_THERM_EVENT_LVT3_N
  SOURCE(0)  = GND
  GATE(0)  = FM_DIMM_EVENT_FET
  DRAIN(0)  = FM_DIMM_EVENT_FET

(kicad_pcb
	(version 20260206)
	(generator "pcbnew")
	(generator_version "10.0")
	(general
		(thickness 1.6)
		(legacy_teardrops no)
	)
	(paper "A4")
	(title_block
		(title "Wiwynn_Tioga_Pass_MB.brd")
		(comment 1 "Tioga Pass / footprints 2691-2693 of 4770")
	)
	(layers
		(0 "F.Cu" signal "TOP")
		(4 "In1.Cu" signal "L2GND")
		(6 "In2.Cu" signal "L3")
		(8 "In3.Cu" signal "L4GND")
		(10 "In4.Cu" signal "L5")
		(12 "In5.Cu" signal "L6GND")
		(14 "In6.Cu" signal "L7VCC")
		(16 "In7.Cu" signal "L8VCC")
		(18 "In8.Cu" signal "L9GND")
		(20 "In9.Cu" signal "L10")
		(22 "In10.Cu" signal "L11GND")
		(24 "In11.Cu" signal "L12")
		(26 "In12.Cu" signal "L13GND")
		(2 "B.Cu" signal "BOTTOM")
		(9 "F.Adhes" user "F.Adhesive")
		(11 "B.Adhes" user "B.Adhesive")
		(13 "F.Paste" user "Package Geometry/Pastemask Top")
		(15 "B.Paste" user "Package Geometry/Pastemask Bottom")
		(5 "F.SilkS" user "Ref Des/Silkscreen Top")
		(7 "B.SilkS" user "Ref Des/Silkscreen Bottom")
		(1 "F.Mask" user "Board Geometry/Soldermask Top")
		(3 "B.Mask" user "Board Geometry/Soldermask Bottom")
		(17 "Dwgs.User" user "User.Drawings")
		(19 "Cmts.User" user "User.Comments")
		(21 "Eco1.User" user "User.Eco1")
		(23 "Eco2.User" user "User.Eco2")
		(25 "Edge.Cuts" user "Board Geometry/Outline")
		(27 "Margin" user)
		(31 "F.CrtYd" user "Package Geometry/Place Bound Top")
		(29 "B.CrtYd" user "Package Geometry/Place Bound Bottom")
		(35 "F.Fab" user "Ref Des/Assembly Top")
		(33 "B.Fab" user "Ref Des/Assembly Bottom")
	)
	(footprint ""
		(layer "B.Cu")
		(at 330.5048 -9.1186 90)
		(property "Reference" "Q4U1"
			(at -0.76327 4.7752 0)
			(unlocked yes)
			(layer "B.SilkS")
			(effects
				(font
					(size 0.7874 0.5842)
					(thickness 0.1524)
				)
				(justify left mirror)
			)
		)
		(property "Value" ""
			(at 0 0 90)
			(layer "B.Fab")
			(effects
				(font
					(size 1.27 1.27)
				)
				(justify mirror)
			)
		)
		(duplicate_pad_numbers_are_jumpers no)
		(fp_circle
			(center 0.508 -0.7874)
			(end 0.508 -0.6604)
			(stroke
				(width 0.254)
				(type default)
			)
			(fill no)
			(layer "B.SilkS")
		)
		(fp_poly
			(pts
				(xy -0.2159 1.7526) (xy -1.5621 1.7526) (xy -1.5621 -0.4572) (xy -0.2159 -0.4572)
			)
			(stroke
				(width 0)
				(type default)
			)
			(fill no)
			(layer "B.CrtYd")
		)
		(fp_line
			(start -0.2159 -0.45466)
			(end -0.2159 1.75514)
			(stroke
				(width 0.1)
				(type default)
			)
			(layer "B.Fab")
		)
		(fp_line
			(start -1.5621 -0.45466)
			(end -0.2159 -0.45466)
			(stroke
				(width 0.1)
				(type default)
			)
			(layer "B.Fab")
		)
		(fp_line
			(start -0.2159 1.75514)
			(end -1.5621 1.75514)
			(stroke
				(width 0.1)
				(type default)
			)
			(layer "B.Fab")
		)
		(fp_line
			(start -1.5621 1.75514)
			(end -1.5621 -0.45466)
			(stroke
				(width 0.1)
				(type default)
			)
			(layer "B.Fab")
		)
		(fp_circle
			(center 0.508 -0.7874)
			(end 0.508 -0.6604)
			(stroke
				(width 0.254)
				(type default)
			)
			(fill no)
			(layer "B.Fab")
		)
		(pad "1" smd rect
			(at 0 0 270)
			(size 1.016 0.381)
			(layers "B.Cu" "B.Mask" "B.Paste")
			(net "GND")
		)
		(pad "2" smd rect
			(at 0 0.65024 270)
			(size 1.016 0.381)
			(layers "B.Cu" "B.Mask" "B.Paste")
			(net "FM_DIMM_EVENT_COD_N")
		)
		(pad "3" smd rect
			(at 0 1.30048 270)
			(size 1.016 0.381)
			(layers "B.Cu" "B.Mask" "B.Paste")
			(net "FM_MEM_THERM_EVENT_LVT3_N")
		)
		(pad "4" smd rect
			(at -1.778 1.30048 270)
			(size 1.016 0.381)
			(layers "B.Cu" "B.Mask" "B.Paste")
			(net "GND")
		)
		(pad "5" smd rect
			(at -1.778 0.65024 270)
			(size 1.016 0.381)
			(layers "B.Cu" "B.Mask" "B.Paste")
			(net "FM_DIMM_EVENT_FET")
		)
		(pad "6" smd rect
			(at -1.778 0 270)
			(size 1.016 0.381)
			(layers "B.Cu" "B.Mask" "B.Paste")
			(net "FM_DIMM_EVENT_FET")
		)
		(zone
			(layer "B.Cu")
			(hatch none 0.5)
			(connect_pads
				(clearance 0)
			)
			(min_thickness 0.25)
			(keepout
				(tracks allowed)
				(vias not_allowed)
				(pads allowed)
				(copperpour not_allowed)
				(footprints allowed)
			)
			(placement
				(enabled no)
				(sheetname "")
			)
			(fill
				(thermal_gap 0.5)
				(thermal_bridge_width 0.5)
				(island_removal_mode 0)
			)
			(polygon
				(pts
					(xy 330.3143 -9.6266) (xy 330.3143 -8.6106) (xy 332.0034 -8.6106) (xy 332.0034 -9.6266)
				)
			)
		)
		(zone
			(layer "B.Cu")
			(hatch none 0.5)
			(connect_pads
				(clearance 0)
			)
			(min_thickness 0.25)
			(keepout
				(tracks allowed)
				(vias not_allowed)
				(pads allowed)
				(copperpour not_allowed)
				(footprints allowed)
			)
			(placement
				(enabled no)
				(sheetname "")
			)
			(fill
				(thermal_gap 0.5)
				(thermal_bridge_width 0.5)
				(island_removal_mode 0)
			)
			(polygon
				(pts
					(xy 330.3143 -7.8486) (xy 330.3143 -6.8326) (xy 332.0034 -6.8326) (xy 332.0034 -7.8486)
				)
			)
		)
	)
	(footprint ""
		(layer "B.Cu")
		(at 252.1585 -149.8092 -90)
		(property "Reference" "C5G61"
			(at -1.14681 0.76708 0)
			(unlocked yes)
			(layer "B.SilkS")
			(effects
				(font
					(size 0.7874 0.5842)
					(thickness 0.1524)
				)
				(justify mirror)
			)
		)
		(property "Value" ""
			(at 0 0 90)
			(layer "B.Fab")
			(effects
				(font
					(size 1.27 1.27)
				)
				(justify mirror)
			)
		)
		(duplicate_pad_numbers_are_jumpers no)
		(fp_rect
			(start 0.4953 1.6002)
			(end -0.4953 -0.2032)
			(stroke
				(width 0)
				(type default)
			)
			(fill no)
			(layer "B.CrtYd")
		)
		(fp_line
			(start -0.4953 1.6002)
			(end 0.4953 1.6002)
			(stroke
				(width 0.1)
				(type default)
			)
			(layer "B.Fab")
		)
		(fp_line
			(start 0.4953 1.6002)
			(end 0.4953 -0.2032)
			(stroke
				(width 0.1)
				(type default)
			)
			(layer "B.Fab")
		)
		(fp_line
			(start -0.4953 -0.2032)
			(end -0.4953 1.6002)
			(stroke
				(width 0.1)
				(type default)
			)
			(layer "B.Fab")
		)
		(fp_line
			(start 0.4953 -0.2032)
			(end -0.4953 -0.2032)
			(stroke
				(width 0.1)
				(type default)
			)
			(layer "B.Fab")
		)
		(pad "1" smd rect
			(at 0 0 90)
			(size 0.762 0.889)
			(layers "B.Cu" "B.Mask" "B.Paste")
			(net "PVDDQ_DEF")
		)
		(pad "2" smd rect
			(at 0 1.397 90)
			(size 0.762 0.889)
			(layers "B.Cu" "B.Mask" "B.Paste")
			(net "GND")
		)
		(zone
			(layer "B.Cu")
			(hatch none 0.5)
			(connect_pads
				(clearance 0)
			)
			(min_thickness 0.25)
			(keepout
				(tracks not_allowed)
				(vias allowed)
				(pads allowed)
				(copperpour not_allowed)
				(footprints allowed)
			)
			(placement
				(enabled no)
				(sheetname "")
			)
			(fill
				(thermal_gap 0.5)
				(thermal_bridge_width 0.5)
				(island_removal_mode 0)
			)
			(polygon
				(pts
					(xy 251.206 -149.4282) (xy 251.714 -149.4282) (xy 251.714 -150.1902) (xy 251.206 -150.1902)
				)
			)
		)
	)
	(footprint ""
		(layer "B.Cu")
		(at 408.559 0.2794 -90)
		(property "Reference" "C2U27"
			(at 0 0 90)
			(layer "B.SilkS")
			(hide yes)
			(effects
				(font
					(size 1.27 1.27)
				)
				(justify mirror)
			)
		)
		(property "Value" ""
			(at 0 0 90)
			(layer "B.Fab")
			(effects
				(font
					(size 1.27 1.27)
				)
				(justify mirror)
			)
		)
		(duplicate_pad_numbers_are_jumpers no)
		(fp_poly
			(pts
				(xy -0.3048 -0.1016) (xy -0.3048 0.9906) (xy 0.3048 0.9906) (xy 0.3048 -0.1016)
			)
			(stroke
				(width 0)
				(type default)
			)
			(fill no)
			(layer "B.CrtYd")
		)
		(fp_line
			(start -0.3048 0.9906)
			(end -0.3048 -0.1016)
			(stroke
				(width 0.1)
				(type default)
			)
			(layer "B.Fab")
		)
		(fp_line
			(start 0.3048 0.9906)
			(end -0.3048 0.9906)
			(stroke
				(width 0.1)
				(type default)
			)
			(layer "B.Fab")
		)
		(fp_line
			(start -0.3048 -0.1016)
			(end 0.3048 -0.1016)
			(stroke
				(width 0.1)
				(type default)
			)
			(layer "B.Fab")
		)
		(fp_line
			(start 0.3048 -0.1016)
			(end 0.3048 0.9906)
			(stroke
				(width 0.1)
				(type default)
			)
			(layer "B.Fab")
		)
		(pad "1" smd rect
			(at 0 0 90)
			(size 0.508 0.508)
			(layers "B.Cu" "B.Mask" "B.Paste")
			(net "P3V3_STBY")
		)
		(pad "2" smd rect
			(at 0 0.889 90)
			(size 0.508 0.508)
			(layers "B.Cu" "B.Mask" "B.Paste")
			(net "GND")
		)
		(zone
			(layer "B.Cu")
			(hatch none 0.5)
			(connect_pads
				(clearance 0)
			)
			(min_thickness 0.25)
			(keepout
				(tracks not_allowed)
				(vias allowed)
				(pads allowed)
				(copperpour not_allowed)
				(footprints allowed)
			)
			(placement
				(enabled no)
				(sheetname "")
			)
			(fill
				(thermal_gap 0.5)
				(thermal_bridge_width 0.5)
				(island_removal_mode 0)
			)
			(polygon
				(pts
					(xy 407.924 0.5334) (xy 407.924 0.0254) (xy 408.305 0.0254) (xy 408.305 0.5334)
				)
			)
		)
		(zone
			(layer "B.Cu")
			(hatch none 0.5)
			(connect_pads
				(clearance 0)
			)
			(min_thickness 0.25)
			(keepout
				(tracks allowed)
				(vias not_allowed)
				(pads allowed)
				(copperpour not_allowed)
				(footprints allowed)
			)
			(placement
				(enabled no)
				(sheetname "")
			)
			(fill
				(thermal_gap 0.5)
				(thermal_bridge_width 0.5)
				(island_removal_mode 0)
			)
			(polygon
				(pts
					(xy 408.305 0.5334) (xy 408.305 0.0254) (xy 407.924 0.0254) (xy 407.924 0.5334)
				)
			)
		)
	)
)
